(kicad_pcb
	(version 20260206)
	(generator "pcbnew")
	(generator_version "10.0")
	(general
		(thickness 1.6)
		(legacy_teardrops no)
	)
	(paper "A4")
	(title_block
		(title "01162023_DA0F0TEBIF0_F0T_Expander_BD_F_brd_V02_OCP.brd")
		(comment 1 "Grand Teton / footprints 9409-9416 of 9728")
	)
	(layers
		(0 "F.Cu" signal "TOP")
		(4 "In1.Cu" signal "GND")
		(6 "In2.Cu" signal "VCC")
		(8 "In3.Cu" signal "VCC1")
		(10 "In4.Cu" signal "GND1")
		(12 "In5.Cu" signal "IN1")
		(14 "In6.Cu" signal "GND2")
		(16 "In7.Cu" signal "IN2")
		(18 "In8.Cu" signal "GND3")
		(20 "In9.Cu" signal "IN3")
		(22 "In10.Cu" signal "GND4")
		(24 "In11.Cu" signal "IN4")
		(26 "In12.Cu" signal "GND5")
		(28 "In13.Cu" signal "IN5")
		(30 "In14.Cu" signal "GND6")
		(32 "In15.Cu" signal "IN6")
		(34 "In16.Cu" signal "GND7")
		(2 "B.Cu" signal "BOTTOM")
		(9 "F.Adhes" user "F.Adhesive")
		(11 "B.Adhes" user "B.Adhesive")
		(13 "F.Paste" user "Package Geometry/Pastemask Top")
		(15 "B.Paste" user "Package Geometry/Pastemask Bottom")
		(5 "F.SilkS" user "Ref Des/Silkscreen Top")
		(7 "B.SilkS" user "Ref Des/Silkscreen Bottom")
		(1 "F.Mask" user "Board Geometry/Soldermask Top")
		(3 "B.Mask" user "Board Geometry/Soldermask Bottom")
		(17 "Dwgs.User" user "User.Drawings")
		(19 "Cmts.User" user "User.Comments")
		(21 "Eco1.User" user "User.Eco1")
		(23 "Eco2.User" user "User.Eco2")
		(25 "Edge.Cuts" user "Board Geometry/Outline")
		(27 "Margin" user)
		(31 "F.CrtYd" user "Package Geometry/Place Bound Top")
		(29 "B.CrtYd" user "Package Geometry/Place Bound Bottom")
		(35 "F.Fab" user "Ref Des/Assembly Top")
		(33 "B.Fab" user "Ref Des/Assembly Bottom")
	)
	(footprint ""
		(layer "B.Cu")
		(at 13.513054 -286.940752 180)
		(property "Reference" "PC989"
			(at 0 0 0)
			(layer "B.SilkS")
			(hide yes)
			(effects
				(font
					(size 1.27 1.27)
				)
				(justify mirror)
			)
		)
		(property "Value" ""
			(at 0 0 0)
			(layer "B.Fab")
			(effects
				(font
					(size 1.27 1.27)
				)
				(justify mirror)
			)
		)
		(duplicate_pad_numbers_are_jumpers no)
		(fp_line
			(start 1.524 0.762)
			(end 1.524 -0.762)
			(stroke
				(width 0.1524)
				(type default)
			)
			(layer "B.SilkS")
		)
		(fp_line
			(start 1.524 -0.762)
			(end -1.524 -0.762)
			(stroke
				(width 0.1524)
				(type default)
			)
			(layer "B.SilkS")
		)
		(fp_line
			(start -1.524 0.762)
			(end 1.524 0.762)
			(stroke
				(width 0.1524)
				(type default)
			)
			(layer "B.SilkS")
		)
		(fp_line
			(start -1.524 -0.762)
			(end -1.524 0.762)
			(stroke
				(width 0.1524)
				(type default)
			)
			(layer "B.SilkS")
		)
		(fp_line
			(start 1.1049 0.724916)
			(end -1.1049 0.724916)
			(stroke
				(width 0.1)
				(type default)
			)
			(layer "B.Fab")
		)
		(fp_line
			(start 1.1049 -0.724916)
			(end 1.1049 0.724916)
			(stroke
				(width 0.1)
				(type default)
			)
			(layer "B.Fab")
		)
		(fp_line
			(start -1.1049 0.724916)
			(end -1.1049 -0.724916)
			(stroke
				(width 0.1)
				(type default)
			)
			(layer "B.Fab")
		)
		(fp_line
			(start -1.1049 -0.724916)
			(end 1.1049 -0.724916)
			(stroke
				(width 0.1)
				(type default)
			)
			(layer "B.Fab")
		)
		(pad "1" smd rect
			(at 0.889 0 180)
			(size 1.016 1.27)
			(layers "B.Cu" "B.Mask" "B.Paste")
			(net "P1V25_PEX0_R")
		)
		(pad "2" smd rect
			(at -0.889 0 180)
			(size 1.016 1.27)
			(layers "B.Cu" "B.Mask" "B.Paste")
			(net "GND")
		)
	)
	(footprint ""
		(layer "B.Cu")
		(at 288.206942 -138.557 90)
		(property "Reference" "C918"
			(at 0 0 90)
			(layer "B.SilkS")
			(hide yes)
			(effects
				(font
					(size 1.27 1.27)
				)
				(justify mirror)
			)
		)
		(property "Value" ""
			(at 0 0 90)
			(layer "B.Fab")
			(effects
				(font
					(size 1.27 1.27)
				)
				(justify mirror)
			)
		)
		(duplicate_pad_numbers_are_jumpers no)
		(fp_line
			(start 0.7874 -0.4064)
			(end -0.7874 -0.4064)
			(stroke
				(width 0.1524)
				(type default)
			)
			(layer "B.SilkS")
		)
		(fp_line
			(start -0.7874 -0.4064)
			(end -0.7874 0.4064)
			(stroke
				(width 0.1524)
				(type default)
			)
			(layer "B.SilkS")
		)
		(fp_line
			(start 0.7874 0.4064)
			(end 0.7874 -0.4064)
			(stroke
				(width 0.1524)
				(type default)
			)
			(layer "B.SilkS")
		)
		(fp_line
			(start -0.7874 0.4064)
			(end 0.7874 0.4064)
			(stroke
				(width 0.1524)
				(type default)
			)
			(layer "B.SilkS")
		)
		(fp_line
			(start 0.67945 -0.305054)
			(end 0.12065 -0.305054)
			(stroke
				(width 0.1)
				(type default)
			)
			(layer "B.Fab")
		)
		(fp_line
			(start 0.12065 -0.305054)
			(end 0.12065 -0.2794)
			(stroke
				(width 0.1)
				(type default)
			)
			(layer "B.Fab")
		)
		(fp_line
			(start -0.12065 -0.3048)
			(end -0.67945 -0.3048)
			(stroke
				(width 0.1)
				(type default)
			)
			(layer "B.Fab")
		)
		(fp_line
			(start -0.67945 -0.3048)
			(end -0.67945 0.3048)
			(stroke
				(width 0.1)
				(type default)
			)
			(layer "B.Fab")
		)
		(fp_line
			(start 0.12065 -0.2794)
			(end -0.12065 -0.2794)
			(stroke
				(width 0.1)
				(type default)
			)
			(layer "B.Fab")
		)
		(fp_line
			(start -0.12065 -0.2794)
			(end -0.12065 -0.3048)
			(stroke
				(width 0.1)
				(type default)
			)
			(layer "B.Fab")
		)
		(fp_line
			(start 0.12065 0.2794)
			(end 0.12065 0.3048)
			(stroke
				(width 0.1)
				(type default)
			)
			(layer "B.Fab")
		)
		(fp_line
			(start -0.120396 0.2794)
			(end 0.12065 0.2794)
			(stroke
				(width 0.1)
				(type default)
			)
			(layer "B.Fab")
		)
		(fp_line
			(start 0.67945 0.3048)
			(end 0.67945 -0.305054)
			(stroke
				(width 0.1)
				(type default)
			)
			(layer "B.Fab")
		)
		(fp_line
			(start 0.12065 0.3048)
			(end 0.67945 0.3048)
			(stroke
				(width 0.1)
				(type default)
			)
			(layer "B.Fab")
		)
		(fp_line
			(start -0.120396 0.3048)
			(end -0.120396 0.2794)
			(stroke
				(width 0.1)
				(type default)
			)
			(layer "B.Fab")
		)
		(fp_line
			(start -0.67945 0.3048)
			(end -0.120396 0.3048)
			(stroke
				(width 0.1)
				(type default)
			)
			(layer "B.Fab")
		)
		(pad "1" smd circle
			(at 0.40005 0 270)
			(size 0 0)
			(layers "B.Cu" "B.Mask" "B.Paste")
			(net "P3V3_AUX")
		)
		(pad "2" smd circle
			(at -0.40005 0 270)
			(size 0 0)
			(layers "B.Cu" "B.Mask" "B.Paste")
			(net "GND")
		)
	)
	(footprint ""
		(layer "B.Cu")
		(at 124.731526 -282.170124 90)
		(property "Reference" "R6764"
			(at 0 0 90)
			(layer "B.SilkS")
			(hide yes)
			(effects
				(font
					(size 1.27 1.27)
				)
				(justify mirror)
			)
		)
		(property "Value" ""
			(at 0 0 90)
			(layer "B.Fab")
			(effects
				(font
					(size 1.27 1.27)
				)
				(justify mirror)
			)
		)
		(duplicate_pad_numbers_are_jumpers no)
		(fp_line
			(start 0.7874 -0.4064)
			(end -0.7874 -0.4064)
			(stroke
				(width 0.1524)
				(type default)
			)
			(layer "B.SilkS")
		)
		(fp_line
			(start -0.7874 -0.4064)
			(end -0.7874 0.4064)
			(stroke
				(width 0.1524)
				(type default)
			)
			(layer "B.SilkS")
		)
		(fp_line
			(start 0.7874 0.4064)
			(end 0.7874 -0.4064)
			(stroke
				(width 0.1524)
				(type default)
			)
			(layer "B.SilkS")
		)
		(fp_line
			(start -0.7874 0.4064)
			(end 0.7874 0.4064)
			(stroke
				(width 0.1524)
				(type default)
			)
			(layer "B.SilkS")
		)
		(fp_line
			(start 0.67945 -0.305054)
			(end 0.12065 -0.305054)
			(stroke
				(width 0.1)
				(type default)
			)
			(layer "B.Fab")
		)
		(fp_line
			(start 0.12065 -0.305054)
			(end 0.12065 -0.2794)
			(stroke
				(width 0.1)
				(type default)
			)
			(layer "B.Fab")
		)
		(fp_line
			(start -0.12065 -0.3048)
			(end -0.67945 -0.3048)
			(stroke
				(width 0.1)
				(type default)
			)
			(layer "B.Fab")
		)
		(fp_line
			(start -0.67945 -0.3048)
			(end -0.67945 0.3048)
			(stroke
				(width 0.1)
				(type default)
			)
			(layer "B.Fab")
		)
		(fp_line
			(start 0.12065 -0.2794)
			(end -0.12065 -0.2794)
			(stroke
				(width 0.1)
				(type default)
			)
			(layer "B.Fab")
		)
		(fp_line
			(start -0.12065 -0.2794)
			(end -0.12065 -0.3048)
			(stroke
				(width 0.1)
				(type default)
			)
			(layer "B.Fab")
		)
		(fp_line
			(start 0.12065 0.2794)
			(end 0.12065 0.3048)
			(stroke
				(width 0.1)
				(type default)
			)
			(layer "B.Fab")
		)
		(fp_line
			(start -0.120396 0.2794)
			(end 0.12065 0.2794)
			(stroke
				(width 0.1)
				(type default)
			)
			(layer "B.Fab")
		)
		(fp_line
			(start 0.67945 0.3048)
			(end 0.67945 -0.305054)
			(stroke
				(width 0.1)
				(type default)
			)
			(layer "B.Fab")
		)
		(fp_line
			(start 0.12065 0.3048)
			(end 0.67945 0.3048)
			(stroke
				(width 0.1)
				(type default)
			)
			(layer "B.Fab")
		)
		(fp_line
			(start -0.120396 0.3048)
			(end -0.120396 0.2794)
			(stroke
				(width 0.1)
				(type default)
			)
			(layer "B.Fab")
		)
		(fp_line
			(start -0.67945 0.3048)
			(end -0.120396 0.3048)
			(stroke
				(width 0.1)
				(type default)
			)
			(layer "B.Fab")
		)
		(pad "1" smd circle
			(at 0.40005 0 270)
			(size 0 0)
			(layers "B.Cu" "B.Mask" "B.Paste")
			(net "P0V8_PEX1_VCC1")
		)
		(pad "2" smd circle
			(at -0.40005 0 270)
			(size 0 0)
			(layers "B.Cu" "B.Mask" "B.Paste")
			(net "P0V8_PEX0_EN3")
		)
	)
	(footprint ""
		(layer "B.Cu")
		(at 108.171996 -325.148194 -90)
		(property "Reference" "C4215"
			(at 0 0 90)
			(layer "B.SilkS")
			(hide yes)
			(effects
				(font
					(size 1.27 1.27)
				)
				(justify mirror)
			)
		)
		(property "Value" ""
			(at 0 0 90)
			(layer "B.Fab")
			(effects
				(font
					(size 1.27 1.27)
				)
				(justify mirror)
			)
		)
		(duplicate_pad_numbers_are_jumpers no)
		(fp_line
			(start -1.2954 0.5842)
			(end 1.2954 0.5842)
			(stroke
				(width 0.1524)
				(type default)
			)
			(layer "B.SilkS")
		)
		(fp_line
			(start 1.2954 0.5842)
			(end 1.2954 -0.5842)
			(stroke
				(width 0.1524)
				(type default)
			)
			(layer "B.SilkS")
		)
		(fp_line
			(start -1.2954 -0.5842)
			(end -1.2954 0.5842)
			(stroke
				(width 0.1524)
				(type default)
			)
			(layer "B.SilkS")
		)
		(fp_line
			(start 1.2954 -0.5842)
			(end -1.2954 -0.5842)
			(stroke
				(width 0.1524)
				(type default)
			)
			(layer "B.SilkS")
		)
		(fp_line
			(start -0.8636 0.4572)
			(end 0.8636 0.4572)
			(stroke
				(width 0.1)
				(type default)
			)
			(layer "B.Fab")
		)
		(fp_line
			(start 0.8636 0.4572)
			(end 0.8636 0.4064)
			(stroke
				(width 0.1)
				(type default)
			)
			(layer "B.Fab")
		)
		(fp_line
			(start -1.1938 0.4064)
			(end -0.8636 0.4064)
			(stroke
				(width 0.1)
				(type default)
			)
			(layer "B.Fab")
		)
		(fp_line
			(start -0.8636 0.4064)
			(end -0.8636 0.4572)
			(stroke
				(width 0.1)
				(type default)
			)
			(layer "B.Fab")
		)
		(fp_line
			(start 0.8636 0.4064)
			(end 1.1938 0.4064)
			(stroke
				(width 0.1)
				(type default)
			)
			(layer "B.Fab")
		)
		(fp_line
			(start 1.1938 0.4064)
			(end 1.1938 -0.4064)
			(stroke
				(width 0.1)
				(type default)
			)
			(layer "B.Fab")
		)
		(fp_line
			(start -1.1938 -0.4064)
			(end -1.1938 0.4064)
			(stroke
				(width 0.1)
				(type default)
			)
			(layer "B.Fab")
		)
		(fp_line
			(start -0.8636 -0.4064)
			(end -1.1938 -0.4064)
			(stroke
				(width 0.1)
				(type default)
			)
			(layer "B.Fab")
		)
		(fp_line
			(start 0.8636 -0.4064)
			(end 0.8636 -0.4572)
			(stroke
				(width 0.1)
				(type default)
			)
			(layer "B.Fab")
		)
		(fp_line
			(start 1.1938 -0.4064)
			(end 0.8636 -0.4064)
			(stroke
				(width 0.1)
				(type default)
			)
			(layer "B.Fab")
		)
		(fp_line
			(start -0.8636 -0.4572)
			(end -0.8636 -0.4064)
			(stroke
				(width 0.1)
				(type default)
			)
			(layer "B.Fab")
		)
		(fp_line
			(start 0.8636 -0.4572)
			(end -0.8636 -0.4572)
			(stroke
				(width 0.1)
				(type default)
			)
			(layer "B.Fab")
		)
		(pad "1" smd rect
			(at 0.7366 0 180)
			(size 0.7112 0.8128)
			(layers "B.Cu" "B.Mask" "B.Paste")
			(net "P0V8_SERDES_VDDA_PEX0_C9")
		)
		(pad "2" smd rect
			(at -0.7366 0 180)
			(size 0.7112 0.8128)
			(layers "B.Cu" "B.Mask" "B.Paste")
			(net "GND")
		)
	)
	(footprint ""
		(layer "B.Cu")
		(at 12.458446 -214.304372 90)
		(property "Reference" "R6565"
			(at 0 0 90)
			(layer "B.SilkS")
			(hide yes)
			(effects
				(font
					(size 1.27 1.27)
				)
				(justify mirror)
			)
		)
		(property "Value" ""
			(at 0 0 90)
			(layer "B.Fab")
			(effects
				(font
					(size 1.27 1.27)
				)
				(justify mirror)
			)
		)
		(duplicate_pad_numbers_are_jumpers no)
		(fp_line
			(start 0.7874 -0.4064)
			(end -0.7874 -0.4064)
			(stroke
				(width 0.1524)
				(type default)
			)
			(layer "B.SilkS")
		)
		(fp_line
			(start -0.7874 -0.4064)
			(end -0.7874 0.4064)
			(stroke
				(width 0.1524)
				(type default)
			)
			(layer "B.SilkS")
		)
		(fp_line
			(start 0.7874 0.4064)
			(end 0.7874 -0.4064)
			(stroke
				(width 0.1524)
				(type default)
			)
			(layer "B.SilkS")
		)
		(fp_line
			(start -0.7874 0.4064)
			(end 0.7874 0.4064)
			(stroke
				(width 0.1524)
				(type default)
			)
			(layer "B.SilkS")
		)
		(fp_line
			(start 0.67945 -0.305054)
			(end 0.12065 -0.305054)
			(stroke
				(width 0.1)
				(type default)
			)
			(layer "B.Fab")
		)
		(fp_line
			(start 0.12065 -0.305054)
			(end 0.12065 -0.2794)
			(stroke
				(width 0.1)
				(type default)
			)
			(layer "B.Fab")
		)
		(fp_line
			(start -0.12065 -0.3048)
			(end -0.67945 -0.3048)
			(stroke
				(width 0.1)
				(type default)
			)
			(layer "B.Fab")
		)
		(fp_line
			(start -0.67945 -0.3048)
			(end -0.67945 0.3048)
			(stroke
				(width 0.1)
				(type default)
			)
			(layer "B.Fab")
		)
		(fp_line
			(start 0.12065 -0.2794)
			(end -0.12065 -0.2794)
			(stroke
				(width 0.1)
				(type default)
			)
			(layer "B.Fab")
		)
		(fp_line
			(start -0.12065 -0.2794)
			(end -0.12065 -0.3048)
			(stroke
				(width 0.1)
				(type default)
			)
			(layer "B.Fab")
		)
		(fp_line
			(start 0.12065 0.2794)
			(end 0.12065 0.3048)
			(stroke
				(width 0.1)
				(type default)
			)
			(layer "B.Fab")
		)
		(fp_line
			(start -0.120396 0.2794)
			(end 0.12065 0.2794)
			(stroke
				(width 0.1)
				(type default)
			)
			(layer "B.Fab")
		)
		(fp_line
			(start 0.67945 0.3048)
			(end 0.67945 -0.305054)
			(stroke
				(width 0.1)
				(type default)
			)
			(layer "B.Fab")
		)
		(fp_line
			(start 0.12065 0.3048)
			(end 0.67945 0.3048)
			(stroke
				(width 0.1)
				(type default)
			)
			(layer "B.Fab")
		)
		(fp_line
			(start -0.120396 0.3048)
			(end -0.120396 0.2794)
			(stroke
				(width 0.1)
				(type default)
			)
			(layer "B.Fab")
		)
		(fp_line
			(start -0.67945 0.3048)
			(end -0.120396 0.3048)
			(stroke
				(width 0.1)
				(type default)
			)
			(layer "B.Fab")
		)
		(pad "1" smd circle
			(at 0.40005 0 270)
			(size 0 0)
			(layers "B.Cu" "B.Mask" "B.Paste")
			(net "P3V3_AUX")
		)
		(pad "2" smd circle
			(at -0.40005 0 270)
			(size 0 0)
			(layers "B.Cu" "B.Mask" "B.Paste")
			(net "PEX0_P1V8_PLL_EN")
		)
	)
	(footprint ""
		(layer "B.Cu")
		(at 132.25399 -223.937068 90)
		(property "Reference" "R3459"
			(at 0 0 90)
			(layer "B.SilkS")
			(hide yes)
			(effects
				(font
					(size 1.27 1.27)
				)
				(justify mirror)
			)
		)
		(property "Value" ""
			(at 0 0 90)
			(layer "B.Fab")
			(effects
				(font
					(size 1.27 1.27)
				)
				(justify mirror)
			)
		)
		(duplicate_pad_numbers_are_jumpers no)
		(fp_line
			(start 0.7874 -0.4064)
			(end -0.7874 -0.4064)
			(stroke
				(width 0.1524)
				(type default)
			)
			(layer "B.SilkS")
		)
		(fp_line
			(start -0.7874 -0.4064)
			(end -0.7874 0.4064)
			(stroke
				(width 0.1524)
				(type default)
			)
			(layer "B.SilkS")
		)
		(fp_line
			(start 0.7874 0.4064)
			(end 0.7874 -0.4064)
			(stroke
				(width 0.1524)
				(type default)
			)
			(layer "B.SilkS")
		)
		(fp_line
			(start -0.7874 0.4064)
			(end 0.7874 0.4064)
			(stroke
				(width 0.1524)
				(type default)
			)
			(layer "B.SilkS")
		)
		(fp_line
			(start 0.67945 -0.305054)
			(end 0.12065 -0.305054)
			(stroke
				(width 0.1)
				(type default)
			)
			(layer "B.Fab")
		)
		(fp_line
			(start 0.12065 -0.305054)
			(end 0.12065 -0.2794)
			(stroke
				(width 0.1)
				(type default)
			)
			(layer "B.Fab")
		)
		(fp_line
			(start -0.12065 -0.3048)
			(end -0.67945 -0.3048)
			(stroke
				(width 0.1)
				(type default)
			)
			(layer "B.Fab")
		)
		(fp_line
			(start -0.67945 -0.3048)
			(end -0.67945 0.3048)
			(stroke
				(width 0.1)
				(type default)
			)
			(layer "B.Fab")
		)
		(fp_line
			(start 0.12065 -0.2794)
			(end -0.12065 -0.2794)
			(stroke
				(width 0.1)
				(type default)
			)
			(layer "B.Fab")
		)
		(fp_line
			(start -0.12065 -0.2794)
			(end -0.12065 -0.3048)
			(stroke
				(width 0.1)
				(type default)
			)
			(layer "B.Fab")
		)
		(fp_line
			(start 0.12065 0.2794)
			(end 0.12065 0.3048)
			(stroke
				(width 0.1)
				(type default)
			)
			(layer "B.Fab")
		)
		(fp_line
			(start -0.120396 0.2794)
			(end 0.12065 0.2794)
			(stroke
				(width 0.1)
				(type default)
			)
			(layer "B.Fab")
		)
		(fp_line
			(start 0.67945 0.3048)
			(end 0.67945 -0.305054)
			(stroke
				(width 0.1)
				(type default)
			)
			(layer "B.Fab")
		)
		(fp_line
			(start 0.12065 0.3048)
			(end 0.67945 0.3048)
			(stroke
				(width 0.1)
				(type default)
			)
			(layer "B.Fab")
		)
		(fp_line
			(start -0.120396 0.3048)
			(end -0.120396 0.2794)
			(stroke
				(width 0.1)
				(type default)
			)
			(layer "B.Fab")
		)
		(fp_line
			(start -0.67945 0.3048)
			(end -0.120396 0.3048)
			(stroke
				(width 0.1)
				(type default)
			)
			(layer "B.Fab")
		)
		(pad "1" smd circle
			(at 0.40005 0 270)
			(size 0 0)
			(layers "B.Cu" "B.Mask" "B.Paste")
			(net "SPI_MUX_PEX1_EN_N")
		)
		(pad "2" smd circle
			(at -0.40005 0 270)
			(size 0 0)
			(layers "B.Cu" "B.Mask" "B.Paste")
			(net "GND")
		)
	)
	(footprint ""
		(layer "B.Cu")
		(at 283.345636 -296.37482)
		(property "Reference" "C1628"
			(at 0 0 0)
			(layer "B.SilkS")
			(hide yes)
			(effects
				(font
					(size 1.27 1.27)
				)
				(justify mirror)
			)
		)
		(property "Value" ""
			(at 0 0 0)
			(layer "B.Fab")
			(effects
				(font
					(size 1.27 1.27)
				)
				(justify mirror)
			)
		)
		(duplicate_pad_numbers_are_jumpers no)
		(fp_line
			(start -0.299974 -0.150114)
			(end -0.299974 0.150114)
			(stroke
				(width 0.1)
				(type default)
			)
			(layer "B.Fab")
		)
		(fp_line
			(start -0.299974 0.150114)
			(end 0.299974 0.150114)
			(stroke
				(width 0.1)
				(type default)
			)
			(layer "B.Fab")
		)
		(fp_line
			(start 0.299974 -0.150114)
			(end -0.299974 -0.150114)
			(stroke
				(width 0.1)
				(type default)
			)
			(layer "B.Fab")
		)
		(fp_line
			(start 0.299974 0.150114)
			(end 0.299974 -0.150114)
			(stroke
				(width 0.1)
				(type default)
			)
			(layer "B.Fab")
		)
		(pad "1" smd rect
			(at 0.2667 0 180)
			(size 0.3048 0.381)
			(layers "B.Cu" "B.Mask" "B.Paste")
			(net "P0V8_PEX2")
		)
		(pad "2" smd rect
			(at -0.2667 0 180)
			(size 0.3048 0.381)
			(layers "B.Cu" "B.Mask" "B.Paste")
			(net "GND")
		)
	)
	(footprint ""
		(layer "B.Cu")
		(at 418.399976 -289.724846 180)
		(property "Reference" "C3528"
			(at 0 0 0)
			(layer "B.SilkS")
			(hide yes)
			(effects
				(font
					(size 1.27 1.27)
				)
				(justify mirror)
			)
		)
		(property "Value" ""
			(at 0 0 0)
			(layer "B.Fab")
			(effects
				(font
					(size 1.27 1.27)
				)
				(justify mirror)
			)
		)
		(duplicate_pad_numbers_are_jumpers no)
		(fp_line
			(start 0.299974 0.150114)
			(end 0.299974 -0.150114)
			(stroke
				(width 0.1)
				(type default)
			)
			(layer "B.Fab")
		)
		(fp_line
			(start 0.299974 -0.150114)
			(end -0.299974 -0.150114)
			(stroke
				(width 0.1)
				(type default)
			)
			(layer "B.Fab")
		)
		(fp_line
			(start -0.299974 0.150114)
			(end 0.299974 0.150114)
			(stroke
				(width 0.1)
				(type default)
			)
			(layer "B.Fab")
		)
		(fp_line
			(start -0.299974 -0.150114)
			(end -0.299974 0.150114)
			(stroke
				(width 0.1)
				(type default)
			)
			(layer "B.Fab")
		)
		(pad "1" smd rect
			(at 0.2667 0)
			(size 0.3048 0.381)
			(layers "B.Cu" "B.Mask" "B.Paste")
			(net "P1V8_PEX")
		)
		(pad "2" smd rect
			(at -0.2667 0)
			(size 0.3048 0.381)
			(layers "B.Cu" "B.Mask" "B.Paste")
			(net "GND")
		)
	)
)
